FILE_TYPE = CONNECTIVITY;
{Allegro Design Entry HDL 17.4-2019 S026 (4007227) 1/17/2022}
"PAGE_NUMBER" = 400;
0"NC";
1"GND\g";
2"P1V8_CPU1_RT_1D\g";
3"GND\g";
4"GND\g";
5"RT_CPU1_P0_VQPS";
6"GND\g";
7"GND\g";
8"P0V9_CPU1_RT0_2A\g";
9"P0V9_CPU1_RT_2D\g";
10"P0V9_CPU1_RT0_2A_2D\g";
11"NCF_CPU1_P0_GND";
12"NCF_A1_CPU1_P0_GND";
13"P1V8_CPU1_RT0_1A_1D\g";
14"P1V8_CPU1_RT0_1A\g";
%"PT5161LRS"
"4","(-5925,4450)","0","pure_quanta","I1";
;
LOCATION"U6014"
$SEC"4"
CDS_SEC"4"
PART_TYPE"SMLF"
VALUE"PT5161LRS"
MATERIAL"IC"
NEEDS_NO_SIZE"TRUE"
CDS_LMAN_SYM_OUTLINE"-450,750,400,-750"
CDS_LIB"pure_quanta"
PART_NUMBER"AJ051610U03";
"PWR_2A_20"
$PN"T20"8;
"PWR_2A_19"
$PN"T17"8;
"PWR_2A_18"
$PN"EP20"8;
"PWR_2A_17"
$PN"EP17"8;
"PWR_2A_16"
$PN"EG20"8;
"PWR_2A_15"
$PN"EG17"8;
"PWR_2A_14"
$PN"DY20"8;
"PWR_2A_13"
$PN"DY17"8;
"PWR_2A_12"
$PN"DN20"8;
"PWR_2A_11"
$PN"DN17"8;
"PWR_2A_10"
$PN"DF20"10;
"PWR_2A_9"
$PN"DF17"10;
"PWR_2A_8"
$PN"BD20"10;
"PWR_2A_7"
$PN"BD17"10;
"PWR_2A_6"
$PN"AU20"8;
"PWR_2A_5"
$PN"AU17"8;
"PWR_2A_4"
$PN"AK20"8;
"PWR_2A_3"
$PN"AK17"8;
"PWR_2A_2"
$PN"AC20"8;
"PWR_2A_1"
$PN"AC17"8;
"PWR_1D"
$PN"BV17"13;
"PWR_2D_4"
$PN"CW20"9;
"PWR_2D_3"
$PN"CW17"9;
"PWR_2D_2"
$PN"BL20"9;
"PWR_2D_1"
$PN"BL17"9;
"PWR_1A_5"
$PN"CM20"14;
"PWR_1A_4"
$PN"CM17"14;
"PWR_1A_3"
$PN"CE20"14;
"PWR_1A_2"
$PN"CE17"14;
"PWR_1A_1"
$PN"BV20"14;
"VQPS"
$PN"G1"5;
%"Q_RES"
"2","(-725,2100)","0","pure_quanta","I102";
;
LOCATION"R711"
$SEC"1"
CDS_SEC"1"
PACK_TYPE"0201LF"
VALUE"0"
TOLERANCE"5%"
MATERIAL"CHIP"
WATTAGE"1/20W"
CDS_LIB"pure_quanta"
PART_NUMBER"CS00001JE10";
"A"
$PN"1"12;
"B"
$PN"2"4;
%"Q_RES"
"2","(-875,1550)","0","pure_quanta","I103";
;
LOCATION"R709"
$SEC"1"
CDS_SEC"1"
PACK_TYPE"0201LF"
VALUE"0"
TOLERANCE"5%"
MATERIAL"CHIP"
WATTAGE"1/20W"
CDS_LIB"pure_quanta"
PART_NUMBER"CS00001JE10";
"A"
$PN"1"11;
"B"
$PN"2"3;
%"Q_RES"
"2","(-7075,3650)","0","pure_quanta","I105";
;
LOCATION"R701"
$SEC"1"
CDS_SEC"1"
WATTAGE"1/20W"
PACK_TYPE"0201LF"
MATERIAL"CHIP"
TOLERANCE"1%"
VALUE"200"
CDS_LIB"pure_quanta"
PART_NUMBER"CS12001FE12";
"A"
$PN"1"5;
"B"
$PN"2"1;
%"Q_RES"
"2","(-8100,4200)","0","pure_quanta","I106";
;
LOCATION"R699"
$SEC"1"
CDS_SEC"1"
PACK_TYPE"0201LF"
TOLERANCE"1%"
MATERIAL"EMPTY"
WATTAGE"1/20W"
VALUE"1K"
CDS_LIB"pure_quanta"
PART_NUMBER"CS21001FE07";
"A"
$PN"1"2;
"B"
$PN"2"5;
%"PT5161LRS"
"5","(-1850,3875)","0","pure_quanta","I2";
;
LOCATION"U6014"
$SEC"5"
CDS_SEC"5"
PART_TYPE"SMLF"
VALUE"PT5161LRS"
MATERIAL"IC"
NEEDS_NO_SIZE"TRUE"
CDS_LMAN_SYM_OUTLINE"-350,2150,300,-2150"
CDS_LIB"pure_quanta"
PART_NUMBER"AJ051610U03";
"GND151"
$PN"V35"7;
"GND150"
$PN"V1"7;
"GND149"
$PN"U34"7;
"GND148"
$PN"U2"7;
"GND147"
$PN"T4"7;
"GND146"
$PN"T32"7;
"GND145"
$PN"T22"7;
"GND144"
$PN"T13"7;
"GND143"
$PN"L35"7;
"GND142"
$PN"L1"7;
"GND141"
$PN"K34"7;
"GND140"
$PN"K2"7;
"GND139"
$PN"J4"7;
"GND138"
$PN"J22"7;
"GND137"
$PN"H31"7;
"GND136"
$PN"H19"7;
"GND135"
$PN"H16"7;
"GND134"
$PN"H12"7;
"GND133"
$PN"FJ19"7;
"GND132"
$PN"FJ12"7;
"GND131"
$PN"FF21"7;
"GND130"
$PN"FF14"7;
"GND129"
$PN"FD35"7;
"GND128"
$PN"FD1"7;
"GND127"
$PN"FC9"7;
"GND126"
$PN"FC6"7;
"GND125"
$PN"FC3"7;
"GND124"
$PN"FC28"7;
"GND123"
$PN"FC25"7;
"GND122"
$PN"FC23"7;
"GND121"
$PN"FC19"7;
"GND120"
$PN"FB34"7;
"GND119"
$PN"FB2"7;
"GND118"
$PN"FA32"7;
"GND117"
$PN"FA15"7;
"GND116"
$PN"ET35"7;
"GND115"
$PN"ET1"7;
"GND114"
$PN"ER34"7;
"GND113"
$PN"ER2"7;
"GND112"
$PN"EP4"7;
"GND111"
$PN"EP32"7;
"GND110"
$PN"EP22"7;
"GND109"
$PN"EP13"7;
"GND108"
$PN"EJ35"7;
"GND107"
$PN"EJ1"7;
"GND106"
$PN"EH34"7;
"GND105"
$PN"EH2"7;
"GND104"
$PN"EG4"7;
"GND103"
$PN"EG32"7;
"GND102"
$PN"EG22"7;
"GND101"
$PN"EG13"7;
"GND100"
$PN"EB35"7;
"GND99"
$PN"EB1"7;
"GND98"
$PN"EA34"7;
"GND97"
$PN"EA2"7;
"GND96"
$PN"E33"7;
"GND95"
$PN"E27"7;
"GND94"
$PN"E14"7;
"GND93"
$PN"DY4"7;
"GND92"
$PN"DY32"7;
"GND91"
$PN"DY22"7;
"GND90"
$PN"DY13"7;
"GND89"
$PN"DR35"7;
"GND88"
$PN"DR1"7;
"GND87"
$PN"DP34"7;
"GND86"
$PN"DP2"7;
"GND85"
$PN"DN4"7;
"GND84"
$PN"DN32"7;
"GND83"
$PN"DN22"7;
"NCF_GND12"
$PN"FH34"11;
"NCF_GND11"
$PN"FH2"11;
"NCF_GND10"
$PN"FG35"11;
"NCF_GND9"
$PN"FG1"11;
"NCF_GND8"
$PN"FE34"11;
"NCF_GND7"
$PN"FE2"11;
"NCF_GND6"
$PN"D35"11;
"NCF_GND5"
$PN"D1"11;
"NCF_GND4"
$PN"C34"11;
"NCF_GND3"
$PN"C2"11;
"NCF_GND2"
$PN"A35"11;
"NCF_GND1"
$PN"A1"12;
"GND82"
$PN"DN13"6;
"GND81"
$PN"DH35"6;
"GND80"
$PN"DH1"6;
"GND79"
$PN"DG34"6;
"GND78"
$PN"DG2"6;
"GND77"
$PN"DF4"6;
"GND76"
$PN"DF32"6;
"GND75"
$PN"DF22"6;
"GND74"
$PN"DF13"6;
"GND73"
$PN"DA35"6;
"GND72"
$PN"DA1"6;
"GND71"
$PN"CY34"6;
"GND70"
$PN"CY2"6;
"GND69"
$PN"CW4"6;
"GND68"
$PN"CW32"6;
"GND67"
$PN"CW22"6;
"GND66"
$PN"CW13"6;
"GND65"
$PN"CP35"6;
"GND64"
$PN"CP1"6;
"GND63"
$PN"CN34"6;
"GND62"
$PN"CN2"6;
"GND61"
$PN"CM4"6;
"GND60"
$PN"CM32"6;
"GND59"
$PN"CM22"6;
"GND58"
$PN"CM13"6;
"GND57"
$PN"CG35"6;
"GND56"
$PN"CG1"6;
"GND55"
$PN"CF34"6;
"GND54"
$PN"CF2"6;
"GND53"
$PN"CE4"6;
"GND52"
$PN"CE32"6;
"GND51"
$PN"CE22"6;
"GND50"
$PN"CE13"6;
"GND49"
$PN"BY35"6;
"GND48"
$PN"BY1"6;
"GND47"
$PN"BW34"6;
"GND46"
$PN"BW2"6;
"GND45"
$PN"BV4"6;
"GND44"
$PN"BV32"6;
"GND43"
$PN"BV22"6;
"GND42"
$PN"BV13"6;
"GND41"
$PN"BN35"6;
"GND40"
$PN"BN1"6;
"GND39"
$PN"BM34"6;
"GND38"
$PN"BM2"6;
"GND37"
$PN"BL4"6;
"GND36"
$PN"BL32"6;
"GND35"
$PN"BL22"6;
"GND34"
$PN"BL13"6;
"GND33"
$PN"BF35"6;
"GND32"
$PN"BF1"6;
"GND31"
$PN"BE34"6;
"GND30"
$PN"BE2"6;
"GND29"
$PN"BD4"6;
"GND28"
$PN"BD32"6;
"GND27"
$PN"BD22"6;
"GND26"
$PN"BD13"6;
"GND25"
$PN"B19"6;
"GND24"
$PN"AW35"6;
"GND23"
$PN"AW1"6;
"GND22"
$PN"AV34"6;
"GND21"
$PN"AV2"6;
"GND20"
$PN"AU4"6;
"GND19"
$PN"AU32"6;
"GND18"
$PN"AU22"6;
"GND17"
$PN"AU13"6;
"GND16"
$PN"AM35"6;
"GND15"
$PN"AM1"6;
"GND14"
$PN"AL34"6;
"GND13"
$PN"AL2"6;
"GND12"
$PN"AK4"6;
"GND11"
$PN"AK32"6;
"GND10"
$PN"AK22"6;
"GND9"
$PN"AK13"6;
"GND8"
$PN"AE35"6;
"GND7"
$PN"AE1"6;
"GND6"
$PN"AD34"6;
"GND5"
$PN"AD2"6;
"GND4"
$PN"AC4"6;
"GND3"
$PN"AC32"6;
"GND2"
$PN"AC22"6;
"GND1"
$PN"AC13"6;
%"P1V0"
"1","(-7775,4700)","0","pure_quanta_power","I21";
;
HDL_POWER"P1V8_CPU1_RT0_1A_1D"
CDS_LIB"pure_quanta_power";
"A"13;
%"UNIVERSAL_GND"
"1","(-7075,3400)","0","pure_quanta_power","I25";
;
CDS_LIB"pure_quanta_power"
HDL_POWER"GND";
"A"1;
%"P1V0"
"1","(-8100,4425)","0","pure_quanta_power","I27";
;
HDL_POWER"P1V8_CPU1_RT_1D"
CDS_LIB"pure_quanta_power";
"A"2;
%"UNIVERSAL_GND"
"1","(-2550,1625)","0","pure_quanta_power","I3";
;
CDS_LIB"pure_quanta_power"
HDL_POWER"GND";
"A"6;
%"UNIVERSAL_GND"
"1","(-500,2350)","0","pure_quanta_power","I4";
;
CDS_LIB"pure_quanta_power"
HDL_POWER"GND";
"A"7;
%"VCC_CORE"
"1","(-4100,5325)","0","pure_quanta_power","I40";
;
HDL_POWER"P0V9_CPU1_RT0_2A"
CDS_LIB"pure_quanta_power";
"A"8;
%"UNIVERSAL_GND"
"1","(-875,1250)","0","pure_quanta_power","I6";
;
CDS_LIB"pure_quanta_power"
HDL_POWER"GND";
"A"3;
%"P1V0"
"1","(-4075,4100)","0","pure_quanta_power","I61";
;
HDL_POWER"P0V9_CPU1_RT_2D"
CDS_LIB"pure_quanta_power";
"A"9;
%"UNIVERSAL_GND"
"1","(-725,1800)","0","pure_quanta_power","I8";
;
CDS_LIB"pure_quanta_power"
HDL_POWER"GND";
"A"4;
%"VCC_CORE"
"1","(-4675,4850)","0","pure_quanta_power","I97";
;
HDL_POWER"P0V9_CPU1_RT0_2A_2D"
CDS_LIB"pure_quanta_power";
"A"10;
%"P1V0"
"1","(-7200,5150)","0","pure_quanta_power","I98";
;
HDL_POWER"P1V8_CPU1_RT0_1A"
CDS_LIB"pure_quanta_power";
"A"14;
END.
